# S9S_MB_2U (Grand Teton) — schematic netlist excerpt (pin names and nets, part order shuffled) for the footprints in the layout excerpt that follows; sources: Cadence DE-HDL packaged netlist, KiCad conversion of 03242023_DA0F0TMBIJ0_F0T_Motherboard_J_brd_V01_OCP.brd

R515  Q_RES  10K 1% CHIP  pkg 0402LF  page 127 : A = PD_PIROM_CPU0_ADDR0 ; B = GND
R3535  Q_RES  2.2K 5% CHIP  pkg 0402LF  page 231 : A = P3V3_AUX ; B = SMB_SENSOR_E1S_3V3AUX_SCL

(kicad_pcb
	(version 20260206)
	(generator "pcbnew")
	(generator_version "10.0")
	(general
		(thickness 1.6)
		(legacy_teardrops no)
	)
	(paper "A4")
	(title_block
		(title "03242023_DA0F0TMBIJ0_F0T_Motherboard_J_brd_V01_OCP.brd")
		(comment 1 "Grand Teton / footprints 1398-1399 of 6105")
	)
	(layers
		(0 "F.Cu" signal "TOP")
		(4 "In1.Cu" signal "GND")
		(6 "In2.Cu" signal "IN1")
		(8 "In3.Cu" signal "GND1")
		(10 "In4.Cu" signal "IN2")
		(12 "In5.Cu" signal "GND2")
		(14 "In6.Cu" signal "IN3")
		(16 "In7.Cu" signal "GND3")
		(18 "In8.Cu" signal "VCC")
		(20 "In9.Cu" signal "VCC1")
		(22 "In10.Cu" signal "GND4")
		(24 "In11.Cu" signal "IN4")
		(26 "In12.Cu" signal "GND5")
		(28 "In13.Cu" signal "IN5")
		(30 "In14.Cu" signal "GND6")
		(32 "In15.Cu" signal "IN6")
		(34 "In16.Cu" signal "GND7")
		(2 "B.Cu" signal "BOTTOM")
		(9 "F.Adhes" user "F.Adhesive")
		(11 "B.Adhes" user "B.Adhesive")
		(13 "F.Paste" user "Package Geometry/Pastemask Top")
		(15 "B.Paste" user "Package Geometry/Pastemask Bottom")
		(5 "F.SilkS" user "Ref Des/Silkscreen Top")
		(7 "B.SilkS" user "Ref Des/Silkscreen Bottom")
		(1 "F.Mask" user "Board Geometry/Soldermask Top")
		(3 "B.Mask" user "Board Geometry/Soldermask Bottom")
		(17 "Dwgs.User" user "User.Drawings")
		(19 "Cmts.User" user "User.Comments")
		(21 "Eco1.User" user "User.Eco1")
		(23 "Eco2.User" user "User.Eco2")
		(25 "Edge.Cuts" user "Board Geometry/Outline")
		(27 "Margin" user)
		(31 "F.CrtYd" user "Package Geometry/Place Bound Top")
		(29 "B.CrtYd" user "Package Geometry/Place Bound Bottom")
		(35 "F.Fab" user "Ref Des/Assembly Top")
		(33 "B.Fab" user "Ref Des/Assembly Bottom")
	)
	(footprint ""
		(layer "F.Cu")
		(at 111.332772 -126.678182)
		(property "Reference" "R3535"
			(at 0 0 0)
			(layer "F.SilkS")
			(hide yes)
			(effects
				(font
					(size 1.27 1.27)
				)
			)
		)
		(property "Value" ""
			(at 0 0 0)
			(layer "F.Fab")
			(effects
				(font
					(size 1.27 1.27)
				)
			)
		)
		(duplicate_pad_numbers_are_jumpers no)
		(fp_line
			(start -0.7874 -0.4064)
			(end 0.7874 -0.4064)
			(stroke
				(width 0.1524)
				(type default)
			)
			(layer "F.SilkS")
		)
		(fp_line
			(start -0.7874 0.4064)
			(end -0.7874 -0.4064)
			(stroke
				(width 0.1524)
				(type default)
			)
			(layer "F.SilkS")
		)
		(fp_line
			(start 0.7874 -0.4064)
			(end 0.7874 0.4064)
			(stroke
				(width 0.1524)
				(type default)
			)
			(layer "F.SilkS")
		)
		(fp_line
			(start 0.7874 0.4064)
			(end -0.7874 0.4064)
			(stroke
				(width 0.1524)
				(type default)
			)
			(layer "F.SilkS")
		)
		(fp_line
			(start -0.67945 -0.305054)
			(end -0.12065 -0.305054)
			(stroke
				(width 0.1)
				(type default)
			)
			(layer "F.Fab")
		)
		(fp_line
			(start -0.67945 0.3048)
			(end -0.67945 -0.305054)
			(stroke
				(width 0.1)
				(type default)
			)
			(layer "F.Fab")
		)
		(fp_line
			(start -0.12065 -0.305054)
			(end -0.12065 -0.2794)
			(stroke
				(width 0.1)
				(type default)
			)
			(layer "F.Fab")
		)
		(fp_line
			(start -0.12065 -0.2794)
			(end 0.12065 -0.2794)
			(stroke
				(width 0.1)
				(type default)
			)
			(layer "F.Fab")
		)
		(fp_line
			(start -0.12065 0.2794)
			(end -0.12065 0.3048)
			(stroke
				(width 0.1)
				(type default)
			)
			(layer "F.Fab")
		)
		(fp_line
			(start -0.12065 0.3048)
			(end -0.67945 0.3048)
			(stroke
				(width 0.1)
				(type default)
			)
			(layer "F.Fab")
		)
		(fp_line
			(start 0.120396 0.2794)
			(end -0.12065 0.2794)
			(stroke
				(width 0.1)
				(type default)
			)
			(layer "F.Fab")
		)
		(fp_line
			(start 0.120396 0.3048)
			(end 0.120396 0.2794)
			(stroke
				(width 0.1)
				(type default)
			)
			(layer "F.Fab")
		)
		(fp_line
			(start 0.12065 -0.3048)
			(end 0.67945 -0.3048)
			(stroke
				(width 0.1)
				(type default)
			)
			(layer "F.Fab")
		)
		(fp_line
			(start 0.12065 -0.2794)
			(end 0.12065 -0.3048)
			(stroke
				(width 0.1)
				(type default)
			)
			(layer "F.Fab")
		)
		(fp_line
			(start 0.67945 -0.3048)
			(end 0.67945 0.3048)
			(stroke
				(width 0.1)
				(type default)
			)
			(layer "F.Fab")
		)
		(fp_line
			(start 0.67945 0.3048)
			(end 0.120396 0.3048)
			(stroke
				(width 0.1)
				(type default)
			)
			(layer "F.Fab")
		)
		(pad "1" smd circle
			(at -0.40005 0)
			(size 0 0)
			(layers "F.Cu" "F.Mask" "F.Paste")
			(net "P3V3_AUX")
		)
		(pad "2" smd circle
			(at 0.40005 0)
			(size 0 0)
			(layers "F.Cu" "F.Mask" "F.Paste")
			(net "SMB_SENSOR_E1S_3V3AUX_SCL")
		)
	)
	(footprint ""
		(layer "F.Cu")
		(at 406.124664 -364.151926)
		(property "Reference" "R515"
			(at 0 0 0)
			(layer "F.SilkS")
			(hide yes)
			(effects
				(font
					(size 1.27 1.27)
				)
			)
		)
		(property "Value" ""
			(at 0 0 0)
			(layer "F.Fab")
			(effects
				(font
					(size 1.27 1.27)
				)
			)
		)
		(duplicate_pad_numbers_are_jumpers no)
		(fp_line
			(start -0.7874 -0.4064)
			(end 0.7874 -0.4064)
			(stroke
				(width 0.1524)
				(type default)
			)
			(layer "F.SilkS")
		)
		(fp_line
			(start -0.7874 0.4064)
			(end -0.7874 -0.4064)
			(stroke
				(width 0.1524)
				(type default)
			)
			(layer "F.SilkS")
		)
		(fp_line
			(start 0.7874 -0.4064)
			(end 0.7874 0.4064)
			(stroke
				(width 0.1524)
				(type default)
			)
			(layer "F.SilkS")
		)
		(fp_line
			(start 0.7874 0.4064)
			(end -0.7874 0.4064)
			(stroke
				(width 0.1524)
				(type default)
			)
			(layer "F.SilkS")
		)
		(fp_line
			(start -0.67945 -0.305054)
			(end -0.12065 -0.305054)
			(stroke
				(width 0.1)
				(type default)
			)
			(layer "F.Fab")
		)
		(fp_line
			(start -0.67945 0.3048)
			(end -0.67945 -0.305054)
			(stroke
				(width 0.1)
				(type default)
			)
			(layer "F.Fab")
		)
		(fp_line
			(start -0.12065 -0.305054)
			(end -0.12065 -0.2794)
			(stroke
				(width 0.1)
				(type default)
			)
			(layer "F.Fab")
		)
		(fp_line
			(start -0.12065 -0.2794)
			(end 0.12065 -0.2794)
			(stroke
				(width 0.1)
				(type default)
			)
			(layer "F.Fab")
		)
		(fp_line
			(start -0.12065 0.2794)
			(end -0.12065 0.3048)
			(stroke
				(width 0.1)
				(type default)
			)
			(layer "F.Fab")
		)
		(fp_line
			(start -0.12065 0.3048)
			(end -0.67945 0.3048)
			(stroke
				(width 0.1)
				(type default)
			)
			(layer "F.Fab")
		)
		(fp_line
			(start 0.120396 0.2794)
			(end -0.12065 0.2794)
			(stroke
				(width 0.1)
				(type default)
			)
			(layer "F.Fab")
		)
		(fp_line
			(start 0.120396 0.3048)
			(end 0.120396 0.2794)
			(stroke
				(width 0.1)
				(type default)
			)
			(layer "F.Fab")
		)
		(fp_line
			(start 0.12065 -0.3048)
			(end 0.67945 -0.3048)
			(stroke
				(width 0.1)
				(type default)
			)
			(layer "F.Fab")
		)
		(fp_line
			(start 0.12065 -0.2794)
			(end 0.12065 -0.3048)
			(stroke
				(width 0.1)
				(type default)
			)
			(layer "F.Fab")
		)
		(fp_line
			(start 0.67945 -0.3048)
			(end 0.67945 0.3048)
			(stroke
				(width 0.1)
				(type default)
			)
			(layer "F.Fab")
		)
		(fp_line
			(start 0.67945 0.3048)
			(end 0.120396 0.3048)
			(stroke
				(width 0.1)
				(type default)
			)
			(layer "F.Fab")
		)
		(pad "1" smd circle
			(at -0.40005 0)
			(size 0 0)
			(layers "F.Cu" "F.Mask" "F.Paste")
			(net "PD_PIROM_CPU0_ADDR0")
		)
		(pad "2" smd circle
			(at 0.40005 0)
			(size 0 0)
			(layers "F.Cu" "F.Mask" "F.Paste")
			(net "GND")
		)
	)
)
